(kicad_pcb
	(version 20241229)
	(generator "pcbnew")
	(generator_version "9.0")
	(general
		(thickness 1.6296)
		(legacy_teardrops no)
	)
	(paper "A3")
	(title_block
		(title "Thunderbolt to 10GbE adapter")
		(date "2026-04-21")
		(rev "1.1.0")
		(company "Antmicro Ltd")
		(comment 1 "www.antmicro.com")
		(comment 9 "footprints 473-477 of 703")
	)
	(layers
		(0 "F.Cu" signal)
		(4 "In1.Cu" signal)
		(6 "In2.Cu" signal)
		(8 "In3.Cu" signal)
		(10 "In4.Cu" signal)
		(12 "In5.Cu" signal)
		(14 "In6.Cu" signal)
		(2 "B.Cu" signal)
		(9 "F.Adhes" user "F.Adhesive")
		(11 "B.Adhes" user "B.Adhesive")
		(13 "F.Paste" user)
		(15 "B.Paste" user)
		(5 "F.SilkS" user "F.Silkscreen")
		(7 "B.SilkS" user "B.Silkscreen")
		(1 "F.Mask" user)
		(3 "B.Mask" user)
		(17 "Dwgs.User" user "User.Drawings")
		(19 "Cmts.User" user "User.Comments")
		(21 "Eco1.User" user "User.Eco1")
		(23 "Eco2.User" user "User.Eco2")
		(25 "Edge.Cuts" user)
		(27 "Margin" user)
		(31 "F.CrtYd" user "F.Courtyard")
		(29 "B.CrtYd" user "B.Courtyard")
		(35 "F.Fab" user)
		(33 "B.Fab" user)
	)
	(footprint "antmicro-footprints:TP_SMD_0.75mm"
		(layer "B.Cu")
		(at 157.381866 79.485117 180)
		(property "Reference" "TP31"
			(at -20.718136 -9.114883 0)
			(layer "B.SilkS")
			(effects
				(font
					(size 0.7 0.7)
					(thickness 0.15)
				)
				(justify mirror)
			)
		)
		(property "Value" "TP_0.75mm_SMD"
			(at 0 -1.2 0)
			(layer "B.Fab")
			(effects
				(font
					(size 0.7 0.7)
					(thickness 0.15)
				)
				(justify left bottom mirror)
			)
		)
		(property "Description" "SMT test point"
			(at 0 0 0)
			(layer "B.Fab")
			(hide yes)
			(effects
				(font
					(size 1.27 1.27)
					(thickness 0.15)
				)
				(justify mirror)
			)
		)
		(property "MPN" ""
			(at 0 0 180)
			(unlocked yes)
			(layer "B.Fab")
			(hide yes)
			(effects
				(font
					(size 1 1)
					(thickness 0.15)
				)
				(justify mirror)
			)
		)
		(property "Manufacturer" ""
			(at 0 0 180)
			(unlocked yes)
			(layer "B.Fab")
			(hide yes)
			(effects
				(font
					(size 1 1)
					(thickness 0.15)
				)
				(justify mirror)
			)
		)
		(property "Author" "Antmicro"
			(at 0 0 180)
			(unlocked yes)
			(layer "B.Fab")
			(hide yes)
			(effects
				(font
					(size 1 1)
					(thickness 0.15)
				)
				(justify mirror)
			)
		)
		(property "License" "Apache-2.0"
			(at 0 0 180)
			(unlocked yes)
			(layer "B.Fab")
			(hide yes)
			(effects
				(font
					(size 1 1)
					(thickness 0.15)
				)
				(justify mirror)
			)
		)
		(sheetname "/X710-AT2 Misc/")
		(sheetfile "x710-at2-mics.kicad_sch")
		(attr exclude_from_pos_files exclude_from_bom)
		(fp_circle
			(center 0 0)
			(end 0.475 0)
			(stroke
				(width 0.05)
				(type default)
			)
			(fill no)
			(layer "B.CrtYd")
		)
		(fp_text user "${REFERENCE}"
			(at -0.4 -2.7 0)
			(layer "B.Fab")
			(effects
				(font
					(size 0.7 0.7)
					(thickness 0.15)
				)
				(justify left bottom mirror)
			)
		)
		(fp_text user "Author: Antmicro"
			(at -0.4 -3.901 0)
			(layer "B.Fab")
			(effects
				(font
					(size 0.7 0.7)
					(thickness 0.15)
				)
				(justify left bottom mirror)
			)
		)
		(fp_text user "License: Apache-2.0"
			(at -0.4 -5.101 0)
			(layer "B.Fab")
			(effects
				(font
					(size 0.7 0.7)
					(thickness 0.15)
				)
				(justify left bottom mirror)
			)
		)
		(pad "1" smd circle
			(at 0 0 180)
			(size 0.75 0.75)
			(layers "B.Cu" "B.Mask")
			(net 104 "/X710-AT2 Misc/PHY_TCK")
			(pinfunction "1")
			(pintype "passive")
		)
	)
	(footprint "antmicro-footprints:C_0402_1005Metric"
		(layer "B.Cu")
		(at 163.25 129.25 180)
		(descr "Capacitor SMD 0402")
		(tags "capacitor SMD 0402")
		(property "Reference" "C288"
			(at -4.5 1.75 0)
			(layer "B.SilkS")
			(effects
				(font
					(size 0.7 0.7)
					(thickness 0.15)
				)
				(justify left bottom mirror)
			)
		)
		(property "Value" "C_100n_0402"
			(at -1.022927 -2.155213 0)
			(layer "B.Fab")
			(effects
				(font
					(size 0.7 0.7)
					(thickness 0.15)
				)
				(justify left bottom mirror)
			)
		)
		(property "Datasheet" "https://www.murata.com/products/productdetail?partno=GRM155R61H104KE14%23"
			(at 0 0 0)
			(layer "B.Fab")
			(hide yes)
			(effects
				(font
					(size 1.27 1.27)
					(thickness 0.15)
				)
				(justify mirror)
			)
		)
		(property "Description" "SMD Multilayer Ceramic Capacitor, 0.1 µF, 50 V, 0402 [1005 Metric], ± 10%, X5R, GRM Series"
			(at 0 0 0)
			(layer "B.Fab")
			(hide yes)
			(effects
				(font
					(size 1.27 1.27)
					(thickness 0.15)
				)
				(justify mirror)
			)
		)
		(property "MPN" "GRM155R61H104KE14D"
			(at 0 0 180)
			(unlocked yes)
			(layer "B.Fab")
			(hide yes)
			(effects
				(font
					(size 1 1)
					(thickness 0.15)
				)
				(justify mirror)
			)
		)
		(property "Val" "100n"
			(at 0 0 180)
			(unlocked yes)
			(layer "B.Fab")
			(hide yes)
			(effects
				(font
					(size 1 1)
					(thickness 0.15)
				)
				(justify mirror)
			)
		)
		(property "Voltage" "50V"
			(at 0 0 180)
			(unlocked yes)
			(layer "B.Fab")
			(hide yes)
			(effects
				(font
					(size 1 1)
					(thickness 0.15)
				)
				(justify mirror)
			)
		)
		(property "Dielectric" "X5R"
			(at 0 0 180)
			(unlocked yes)
			(layer "B.Fab")
			(hide yes)
			(effects
				(font
					(size 1 1)
					(thickness 0.15)
				)
				(justify mirror)
			)
		)
		(property "Manufacturer" "Murata"
			(at 0 0 180)
			(unlocked yes)
			(layer "B.Fab")
			(hide yes)
			(effects
				(font
					(size 1 1)
					(thickness 0.15)
				)
				(justify mirror)
			)
		)
		(property "License" "Apache-2.0"
			(at 0 0 180)
			(unlocked yes)
			(layer "B.Fab")
			(hide yes)
			(effects
				(font
					(size 1 1)
					(thickness 0.15)
				)
				(justify mirror)
			)
		)
		(property "Author" "Antmicro"
			(at 0 0 180)
			(unlocked yes)
			(layer "B.Fab")
			(hide yes)
			(effects
				(font
					(size 1 1)
					(thickness 0.15)
				)
				(justify mirror)
			)
		)
		(sheetname "/2xRJ45/")
		(sheetfile "2xrj45.kicad_sch")
		(attr smd)
		(fp_rect
			(start -0.925 0.47)
			(end 0.925 -0.47)
			(stroke
				(width 0.05)
				(type default)
			)
			(fill no)
			(layer "B.CrtYd")
		)
		(fp_line
			(start 0.504 0.25)
			(end 0.504 -0.248)
			(stroke
				(width 0.15)
				(type solid)
			)
			(layer "B.Fab")
		)
		(fp_line
			(start 0.504 -0.248)
			(end -0.494 -0.248)
			(stroke
				(width 0.15)
				(type solid)
			)
			(layer "B.Fab")
		)
		(fp_line
			(start -0.494 0.25)
			(end 0.504 0.25)
			(stroke
				(width 0.15)
				(type solid)
			)
			(layer "B.Fab")
		)
		(fp_line
			(start -0.494 -0.248)
			(end -0.494 0.25)
			(stroke
				(width 0.15)
				(type solid)
			)
			(layer "B.Fab")
		)
		(fp_text user "Author: Antmicro"
			(at -0.939 -3.399 0)
			(layer "B.Fab")
			(effects
				(font
					(size 0.7 0.7)
					(thickness 0.15)
				)
				(justify left bottom mirror)
			)
		)
		(fp_text user "License: Apache-2.0"
			(at -0.939 -5.799 0)
			(layer "B.Fab")
			(effects
				(font
					(size 0.7 0.7)
					(thickness 0.15)
				)
				(justify left bottom mirror)
			)
		)
		(fp_text user "${REFERENCE}"
			(at -0.939 -4.599 0)
			(layer "B.Fab")
			(effects
				(font
					(size 0.7 0.7)
					(thickness 0.15)
				)
				(justify left bottom mirror)
			)
		)
		(pad "1" smd roundrect
			(at -0.48 0 180)
			(size 0.59 0.64)
			(layers "B.Cu" "B.Mask" "B.Paste")
			(roundrect_rratio 0.25)
			(net 23 "GND")
			(pintype "passive")
		)
		(pad "2" smd roundrect
			(at 0.48 0 180)
			(size 0.59 0.64)
			(layers "B.Cu" "B.Mask" "B.Paste")
			(roundrect_rratio 0.25)
			(net 18 "+1V88")
			(pintype "passive")
		)
	)
	(footprint "antmicro-footprints:R_0402_1005Metric"
		(layer "B.Cu")
		(at 155.481866 74.785117 90)
		(descr "Resistor SMD 0402")
		(tags "resistor SMD 0402")
		(property "Reference" "R202"
			(at -8.014883 21.618136 270)
			(layer "B.SilkS")
			(effects
				(font
					(size 0.7 0.7)
					(thickness 0.15)
				)
				(justify mirror)
			)
		)
		(property "Value" "R_8k2_0402"
			(at -1.011843 -1.772047 270)
			(layer "B.Fab")
			(effects
				(font
					(size 0.7 0.7)
					(thickness 0.15)
				)
				(justify left bottom mirror)
			)
		)
		(property "Datasheet" "https://www.bourns.com/docs/product-datasheets/cr.pdf"
			(at 0 0 270)
			(layer "B.Fab")
			(hide yes)
			(effects
				(font
					(size 1.27 1.27)
					(thickness 0.15)
				)
				(justify mirror)
			)
		)
		(property "Description" "SMD Chip Resistor"
			(at 0 0 270)
			(layer "B.Fab")
			(hide yes)
			(effects
				(font
					(size 1.27 1.27)
					(thickness 0.15)
				)
				(justify mirror)
			)
		)
		(property "MPN" "CR0402-FX-8201GLF"
			(at 0 0 90)
			(unlocked yes)
			(layer "B.Fab")
			(hide yes)
			(effects
				(font
					(size 1 1)
					(thickness 0.15)
				)
				(justify mirror)
			)
		)
		(property "Manufacturer" "Bourns"
			(at 0 0 90)
			(unlocked yes)
			(layer "B.Fab")
			(hide yes)
			(effects
				(font
					(size 1 1)
					(thickness 0.15)
				)
				(justify mirror)
			)
		)
		(property "License" "Apache-2.0"
			(at 0 0 90)
			(unlocked yes)
			(layer "B.Fab")
			(hide yes)
			(effects
				(font
					(size 1 1)
					(thickness 0.15)
				)
				(justify mirror)
			)
		)
		(property "Author" "Antmicro"
			(at 0 0 90)
			(unlocked yes)
			(layer "B.Fab")
			(hide yes)
			(effects
				(font
					(size 1 1)
					(thickness 0.15)
				)
				(justify mirror)
			)
		)
		(property "Val" "8k2"
			(at 0 0 90)
			(unlocked yes)
			(layer "B.Fab")
			(hide yes)
			(effects
				(font
					(size 1 1)
					(thickness 0.15)
				)
				(justify mirror)
			)
		)
		(property "Tolerance" "1%"
			(at 0 0 90)
			(unlocked yes)
			(layer "B.Fab")
			(hide yes)
			(effects
				(font
					(size 1 1)
					(thickness 0.15)
				)
				(justify mirror)
			)
		)
		(sheetname "/X710-AT2 10GbE/")
		(sheetfile "x710-at2-10gbe.kicad_sch")
		(attr smd)
		(fp_rect
			(start -0.925 0.47)
			(end 0.925 -0.47)
			(stroke
				(width 0.05)
				(type default)
			)
			(fill no)
			(layer "B.CrtYd")
		)
		(fp_rect
			(start -0.5 0.25)
			(end 0.5 -0.25)
			(stroke
				(width 0.15)
				(type solid)
			)
			(fill no)
			(layer "B.Fab")
		)
		(fp_text user "${REFERENCE}"
			(at -0.95 -3.168 270)
			(layer "B.Fab")
			(effects
				(font
					(size 0.7 0.7)
					(thickness 0.15)
				)
				(justify left bottom mirror)
			)
		)
		(fp_text user "License: Apache-2.0"
			(at -0.95 -5.169 270)
			(layer "B.Fab")
			(effects
				(font
					(size 0.7 0.7)
					(thickness 0.15)
				)
				(justify left bottom mirror)
			)
		)
		(fp_text user "Author: Antmicro"
			(at -0.95 -4.169 270)
			(layer "B.Fab")
			(effects
				(font
					(size 0.7 0.7)
					(thickness 0.15)
				)
				(justify left bottom mirror)
			)
		)
		(pad "1" smd roundrect
			(at -0.48 0 90)
			(size 0.59 0.64)
			(layers "B.Cu" "B.Mask" "B.Paste")
			(roundrect_rratio 0.25)
			(net 64 "/X710-AT2 10GbE/OSC_SEL")
			(pintype "passive")
		)
		(pad "2" smd roundrect
			(at 0.48 0 90)
			(size 0.59 0.64)
			(layers "B.Cu" "B.Mask" "B.Paste")
			(roundrect_rratio 0.25)
			(net 7 "+3V3")
			(pintype "passive")
		)
	)
	(footprint "antmicro-footprints:C_0402_1005Metric"
		(layer "B.Cu")
		(at 156.111866 83.245117 180)
		(descr "Capacitor SMD 0402")
		(tags "capacitor SMD 0402")
		(property "Reference" "C197"
			(at -19.873134 -9.464883 0)
			(layer "B.SilkS")
			(effects
				(font
					(size 0.7 0.7)
					(thickness 0.15)
				)
				(justify mirror)
			)
		)
		(property "Value" "C_1u_25V_0402"
			(at -1.022927 -2.155213 0)
			(layer "B.Fab")
			(effects
				(font
					(size 0.7 0.7)
					(thickness 0.15)
				)
				(justify left bottom mirror)
			)
		)
		(property "Datasheet" "https://www.murata.com/products/productdetail?partno=GRM155R61E105KE11%23"
			(at 0 0 0)
			(layer "B.Fab")
			(hide yes)
			(effects
				(font
					(size 1.27 1.27)
					(thickness 0.15)
				)
				(justify mirror)
			)
		)
		(property "Description" "SMD Multilayer Ceramic Capacitor, 1 µF, 25 V, 0402 [1005 Metric], ± 10%, X5R, GRM Series"
			(at 0 0 0)
			(layer "B.Fab")
			(hide yes)
			(effects
				(font
					(size 1.27 1.27)
					(thickness 0.15)
				)
				(justify mirror)
			)
		)
		(property "MPN" "GRM155R61E105KE11J"
			(at 0 0 180)
			(unlocked yes)
			(layer "B.Fab")
			(hide yes)
			(effects
				(font
					(size 1 1)
					(thickness 0.15)
				)
				(justify mirror)
			)
		)
		(property "Manufacturer" "Murata"
			(at 0 0 180)
			(unlocked yes)
			(layer "B.Fab")
			(hide yes)
			(effects
				(font
					(size 1 1)
					(thickness 0.15)
				)
				(justify mirror)
			)
		)
		(property "License" "Apache-2.0"
			(at 0 0 180)
			(unlocked yes)
			(layer "B.Fab")
			(hide yes)
			(effects
				(font
					(size 1 1)
					(thickness 0.15)
				)
				(justify mirror)
			)
		)
		(property "Author" "Antmicro"
			(at 0 0 180)
			(unlocked yes)
			(layer "B.Fab")
			(hide yes)
			(effects
				(font
					(size 1 1)
					(thickness 0.15)
				)
				(justify mirror)
			)
		)
		(property "Val" "1u"
			(at 0 0 180)
			(unlocked yes)
			(layer "B.Fab")
			(hide yes)
			(effects
				(font
					(size 1 1)
					(thickness 0.15)
				)
				(justify mirror)
			)
		)
		(property "Voltage" "25V"
			(at 0 0 180)
			(unlocked yes)
			(layer "B.Fab")
			(hide yes)
			(effects
				(font
					(size 1 1)
					(thickness 0.15)
				)
				(justify mirror)
			)
		)
		(property "Dielectric" "X5R"
			(at 0 0 180)
			(unlocked yes)
			(layer "B.Fab")
			(hide yes)
			(effects
				(font
					(size 1 1)
					(thickness 0.15)
				)
				(justify mirror)
			)
		)
		(sheetname "/X710-AT2 power/")
		(sheetfile "x710-at2-power.kicad_sch")
		(attr smd)
		(fp_rect
			(start -0.925 0.47)
			(end 0.925 -0.47)
			(stroke
				(width 0.05)
				(type default)
			)
			(fill no)
			(layer "B.CrtYd")
		)
		(fp_line
			(start 0.504 0.25)
			(end 0.504 -0.248)
			(stroke
				(width 0.15)
				(type solid)
			)
			(layer "B.Fab")
		)
		(fp_line
			(start 0.504 -0.248)
			(end -0.494 -0.248)
			(stroke
				(width 0.15)
				(type solid)
			)
			(layer "B.Fab")
		)
		(fp_line
			(start -0.494 0.25)
			(end 0.504 0.25)
			(stroke
				(width 0.15)
				(type solid)
			)
			(layer "B.Fab")
		)
		(fp_line
			(start -0.494 -0.248)
			(end -0.494 0.25)
			(stroke
				(width 0.15)
				(type solid)
			)
			(layer "B.Fab")
		)
		(fp_text user "Author: Antmicro"
			(at -0.939 -3.399 0)
			(layer "B.Fab")
			(effects
				(font
					(size 0.7 0.7)
					(thickness 0.15)
				)
				(justify left bottom mirror)
			)
		)
		(fp_text user "${REFERENCE}"
			(at -0.939 -4.599 0)
			(layer "B.Fab")
			(effects
				(font
					(size 0.7 0.7)
					(thickness 0.15)
				)
				(justify left bottom mirror)
			)
		)
		(fp_text user "License: Apache-2.0"
			(at -0.939 -5.799 0)
			(layer "B.Fab")
			(effects
				(font
					(size 0.7 0.7)
					(thickness 0.15)
				)
				(justify left bottom mirror)
			)
		)
		(pad "1" smd roundrect
			(at -0.48 0 180)
			(size 0.59 0.64)
			(layers "B.Cu" "B.Mask" "B.Paste")
			(roundrect_rratio 0.25)
			(net 23 "GND")
			(pintype "passive")
		)
		(pad "2" smd roundrect
			(at 0.48 0 180)
			(size 0.59 0.64)
			(layers "B.Cu" "B.Mask" "B.Paste")
			(roundrect_rratio 0.25)
			(net 18 "+1V88")
			(pintype "passive")
		)
	)
	(footprint "antmicro-footprints:R_0402_1005Metric"
		(layer "B.Cu")
		(at 145.031866 71.260117)
		(descr "Resistor SMD 0402")
		(tags "resistor SMD 0402")
		(property "Reference" "R125"
			(at 18.468134 8.039883 180)
			(layer "B.SilkS")
			(effects
				(font
					(size 0.7 0.7)
					(thickness 0.15)
				)
				(justify mirror)
			)
		)
		(property "Value" "R_100R_0402"
			(at -1.011843 -1.772047 180)
			(layer "B.Fab")
			(effects
				(font
					(size 0.7 0.7)
					(thickness 0.15)
				)
				(justify left bottom mirror)
			)
		)
		(property "Datasheet" "https://www.bourns.com/docs/product-datasheets/cr.pdf"
			(at 0 0 180)
			(layer "B.Fab")
			(hide yes)
			(effects
				(font
					(size 1.27 1.27)
					(thickness 0.15)
				)
				(justify mirror)
			)
		)
		(property "Description" "SMD Chip Resistor, 100 ohm, ± 1%, 62.5 mW, 0402 [1005 Metric], Thick Film, General Purpose"
			(at 0 0 180)
			(layer "B.Fab")
			(hide yes)
			(effects
				(font
					(size 1.27 1.27)
					(thickness 0.15)
				)
				(justify mirror)
			)
		)
		(property "MPN" "CR0402-FX-1000GLF"
			(at 0 0 0)
			(unlocked yes)
			(layer "B.Fab")
			(hide yes)
			(effects
				(font
					(size 1 1)
					(thickness 0.15)
				)
				(justify mirror)
			)
		)
		(property "Manufacturer" "Bourns"
			(at 0 0 0)
			(unlocked yes)
			(layer "B.Fab")
			(hide yes)
			(effects
				(font
					(size 1 1)
					(thickness 0.15)
				)
				(justify mirror)
			)
		)
		(property "License" "Apache-2.0"
			(at 0 0 0)
			(unlocked yes)
			(layer "B.Fab")
			(hide yes)
			(effects
				(font
					(size 1 1)
					(thickness 0.15)
				)
				(justify mirror)
			)
		)
		(property "Author" "Antmicro"
			(at 0 0 0)
			(unlocked yes)
			(layer "B.Fab")
			(hide yes)
			(effects
				(font
					(size 1 1)
					(thickness 0.15)
				)
				(justify mirror)
			)
		)
		(property "Val" "100R"
			(at 0 0 0)
			(unlocked yes)
			(layer "B.Fab")
			(hide yes)
			(effects
				(font
					(size 1 1)
					(thickness 0.15)
				)
				(justify mirror)
			)
		)
		(property "Tolerance" "1%"
			(at 0 0 0)
			(unlocked yes)
			(layer "B.Fab")
			(hide yes)
			(effects
				(font
					(size 1 1)
					(thickness 0.15)
				)
				(justify mirror)
			)
		)
		(sheetname "/X710-AT2 RSVD/")
		(sheetfile "x710-at2-rsvd.kicad_sch")
		(attr smd)
		(fp_rect
			(start -0.925 0.47)
			(end 0.925 -0.47)
			(stroke
				(width 0.05)
				(type default)
			)
			(fill no)
			(layer "B.CrtYd")
		)
		(fp_rect
			(start -0.5 0.25)
			(end 0.5 -0.25)
			(stroke
				(width 0.15)
				(type solid)
			)
			(fill no)
			(layer "B.Fab")
		)
		(fp_text user "License: Apache-2.0"
			(at -0.95 -5.169 180)
			(layer "B.Fab")
			(effects
				(font
					(size 0.7 0.7)
					(thickness 0.15)
				)
				(justify left bottom mirror)
			)
		)
		(fp_text user "${REFERENCE}"
			(at -0.95 -3.168 180)
			(layer "B.Fab")
			(effects
				(font
					(size 0.7 0.7)
					(thickness 0.15)
				)
				(justify left bottom mirror)
			)
		)
		(fp_text user "Author: Antmicro"
			(at -0.95 -4.169 180)
			(layer "B.Fab")
			(effects
				(font
					(size 0.7 0.7)
					(thickness 0.15)
				)
				(justify left bottom mirror)
			)
		)
		(pad "1" smd roundrect
			(at -0.48 0)
			(size 0.59 0.64)
			(layers "B.Cu" "B.Mask" "B.Paste")
			(roundrect_rratio 0.25)
			(net 23 "GND")
			(pintype "passive")
		)
		(pad "2" smd roundrect
			(at 0.48 0)
			(size 0.59 0.64)
			(layers "B.Cu" "B.Mask" "B.Paste")
			(roundrect_rratio 0.25)
			(net 96 "/X710-AT2 RSVD/RSVDW1_VSS")
			(pintype "passive")
		)
	)
)
